(kicad_pcb
	(version 20260206)
	(generator "pcbnew")
	(generator_version "10.0")
	(general
		(thickness 1.6)
		(legacy_teardrops no)
	)
	(paper "A4")
	(title_block
		(title "Bryce Canyon_R.DPB_16317-1_OCP.brd")
		(comment 1 "Bryce Canyon / footprints 111-118 of 2099")
	)
	(layers
		(0 "F.Cu" signal "TOP")
		(4 "In1.Cu" signal "L2GND")
		(6 "In2.Cu" signal "L3")
		(8 "In3.Cu" signal "L4VCC")
		(10 "In4.Cu" signal "L5VCC")
		(12 "In5.Cu" signal "L6")
		(14 "In6.Cu" signal "L7GND")
		(2 "B.Cu" signal "BOTTOM")
		(9 "F.Adhes" user "F.Adhesive")
		(11 "B.Adhes" user "B.Adhesive")
		(13 "F.Paste" user "Package Geometry/Pastemask Top")
		(15 "B.Paste" user "Package Geometry/Pastemask Bottom")
		(5 "F.SilkS" user "Ref Des/Silkscreen Top")
		(7 "B.SilkS" user "Ref Des/Silkscreen Bottom")
		(1 "F.Mask" user "Board Geometry/Soldermask Top")
		(3 "B.Mask" user "Board Geometry/Soldermask Bottom")
		(17 "Dwgs.User" user "User.Drawings")
		(19 "Cmts.User" user "User.Comments")
		(21 "Eco1.User" user "User.Eco1")
		(23 "Eco2.User" user "User.Eco2")
		(25 "Edge.Cuts" user "Board Geometry/Outline")
		(27 "Margin" user)
		(31 "F.CrtYd" user "Package Geometry/Place Bound Top")
		(29 "B.CrtYd" user "Package Geometry/Place Bound Bottom")
		(35 "F.Fab" user "Ref Des/Assembly Top")
		(33 "B.Fab" user "Ref Des/Assembly Bottom")
	)
	(footprint ""
		(layer "F.Cu")
		(at 416.284664 -244.660674 -90)
		(property "Reference" "C146"
			(at 0 0 270)
			(layer "F.SilkS")
			(hide yes)
			(effects
				(font
					(size 1.27 1.27)
				)
			)
		)
		(property "Value" "SCD01U16V1KX-GP"
			(at -2.8321 -1.7399 270)
			(unlocked yes)
			(layer "F.Fab")
			(hide yes)
			(effects
				(font
					(size 1.016 1.016)
					(thickness 0.1524)
				)
			)
		)
		(property "Device Type" "C0201H13"
			(at -2.8321 -3.2639 270)
			(unlocked yes)
			(layer "F.Fab")
			(hide yes)
			(effects
				(font
					(size 1.016 1.016)
					(thickness 0.1524)
				)
			)
		)
		(duplicate_pad_numbers_are_jumpers no)
		(fp_rect
			(start -0.2794 0.6477)
			(end 0.2794 -0.6477)
			(stroke
				(width 0)
				(type default)
			)
			(fill no)
			(layer "F.CrtYd")
		)
		(fp_rect
			(start -0.2794 0.6477)
			(end 0.2794 -0.6477)
			(stroke
				(width 0)
				(type default)
			)
			(fill no)
			(layer "F.Fab")
		)
		(pad "1" smd custom
			(at 0 -0.2794 270)
			(size 0.0762 0.0762)
			(layers "F.Cu" "F.Mask" "F.Paste")
			(net "SAS_HDD_RX_P9")
			(options
				(clearance outline)
				(anchor circle)
			)
			(primitives
				(gr_poly
					(pts
						(arc
							(start 0.1524 -0.127)
							(mid 0.137521 -0.162921)
							(end 0.1016 -0.1778)
						)
						(arc
							(start -0.1016 -0.1778)
							(mid -0.137521 -0.162921)
							(end -0.1524 -0.127)
						)
						(arc
							(start -0.1524 0.127)
							(mid -0.137521 0.162921)
							(end -0.1016 0.1778)
						)
						(arc
							(start 0.1016 0.1778)
							(mid 0.137521 0.162921)
							(end 0.1524 0.127)
						)
					)
					(width 0)
					(fill yes)
				)
			)
		)
		(pad "2" smd custom
			(at 0 0.2794 270)
			(size 0.0762 0.0762)
			(layers "F.Cu" "F.Mask" "F.Paste")
			(net "PHY_SCC_B_TO_DRV_B_9_DP")
			(options
				(clearance outline)
				(anchor circle)
			)
			(primitives
				(gr_poly
					(pts
						(arc
							(start 0.1524 -0.127)
							(mid 0.137521 -0.162921)
							(end 0.1016 -0.1778)
						)
						(arc
							(start -0.1016 -0.1778)
							(mid -0.137521 -0.162921)
							(end -0.1524 -0.127)
						)
						(arc
							(start -0.1524 0.127)
							(mid -0.137521 0.162921)
							(end -0.1016 0.1778)
						)
						(arc
							(start 0.1016 0.1778)
							(mid 0.137521 0.162921)
							(end 0.1524 0.127)
						)
					)
					(width 0)
					(fill yes)
				)
			)
		)
	)
	(footprint ""
		(layer "F.Cu")
		(at 457.581 -262.001 -90)
		(property "Reference" "R318"
			(at 0 0 270)
			(layer "F.SilkS")
			(hide yes)
			(effects
				(font
					(size 1.27 1.27)
				)
			)
		)
		(property "Value" "2R6F-GP"
			(at -0.0508 -4.8514 270)
			(unlocked yes)
			(layer "F.Fab")
			(hide yes)
			(effects
				(font
					(size 1.016 1.016)
					(thickness 0.1524)
				)
			)
		)
		(property "Device Type" "R1206H26"
			(at 0 -6.3754 270)
			(unlocked yes)
			(layer "F.Fab")
			(hide yes)
			(effects
				(font
					(size 1.016 1.016)
					(thickness 0.1524)
				)
			)
		)
		(duplicate_pad_numbers_are_jumpers no)
		(fp_line
			(start -1.016 2.2352)
			(end -1.016 -2.2352)
			(stroke
				(width 0.1524)
				(type default)
			)
			(layer "F.SilkS")
		)
		(fp_line
			(start 1.016 2.2352)
			(end -1.016 2.2352)
			(stroke
				(width 0.1524)
				(type default)
			)
			(layer "F.SilkS")
		)
		(fp_line
			(start -1.016 -2.2352)
			(end 1.016 -2.2352)
			(stroke
				(width 0.1524)
				(type default)
			)
			(layer "F.SilkS")
		)
		(fp_line
			(start 1.016 -2.2352)
			(end 1.016 2.2352)
			(stroke
				(width 0.1524)
				(type default)
			)
			(layer "F.SilkS")
		)
		(fp_rect
			(start -1.0922 2.3114)
			(end 1.0922 -2.3114)
			(stroke
				(width 0)
				(type default)
			)
			(fill no)
			(layer "F.CrtYd")
		)
		(fp_poly
			(pts
				(xy -1.0922 -2.3114) (xy 1.0922 -2.3114) (xy 1.0922 2.3114) (xy -1.0922 2.3114)
			)
			(stroke
				(width 0)
				(type default)
			)
			(fill no)
			(layer "F.Fab")
		)
		(pad "1" smd rect
			(at 0 -1.397 270)
			(size 1.651 1.27)
			(layers "F.Cu" "F.Mask" "F.Paste")
			(net "P5V_HDD10")
		)
		(pad "2" smd rect
			(at 0 1.397 270)
			(size 1.651 1.27)
			(layers "F.Cu" "F.Mask" "F.Paste")
			(net "5V_PRE_10")
		)
	)
	(footprint ""
		(layer "F.Cu")
		(at 350.766126 -154.70505)
		(property "Reference" "TP116"
			(at 0 0 0)
			(layer "F.SilkS")
			(hide yes)
			(effects
				(font
					(size 1.27 1.27)
				)
			)
		)
		(property "Value" "*"
			(at -0.0508 -1.6764 0)
			(unlocked yes)
			(layer "F.Fab")
			(hide yes)
			(effects
				(font
					(size 1.016 1.016)
					(thickness 0.1524)
				)
			)
		)
		(property "Device Type" "TPAD32"
			(at -0.0508 -3.2004 0)
			(unlocked yes)
			(layer "F.Fab")
			(hide yes)
			(effects
				(font
					(size 1.016 1.016)
					(thickness 0.1524)
				)
			)
		)
		(duplicate_pad_numbers_are_jumpers no)
		(fp_poly
			(pts
				(arc
					(start 0.4064 0)
					(mid -0.4064 0)
					(end 0.4064 0)
				)
			)
			(stroke
				(width 0)
				(type default)
			)
			(fill no)
			(layer "F.CrtYd")
		)
		(fp_poly
			(pts
				(arc
					(start 0.7112 0)
					(mid -0.7112 0)
					(end 0.7112 0)
				)
			)
			(stroke
				(width 0)
				(type default)
			)
			(fill no)
			(layer "F.Fab")
		)
		(pad "1" smd circle
			(at 0 0)
			(size 0.8128 0.8128)
			(layers "F.Cu" "F.Mask" "F.Paste")
			(net "ACT_HDD_19")
		)
	)
	(footprint ""
		(layer "F.Cu")
		(at 365.125 -270.5862 -90)
		(property "Reference" "R272"
			(at 0 0 270)
			(layer "F.SilkS")
			(hide yes)
			(effects
				(font
					(size 1.27 1.27)
				)
			)
		)
		(property "Value" "2R6F-GP"
			(at -0.0508 -4.8514 270)
			(unlocked yes)
			(layer "F.Fab")
			(hide yes)
			(effects
				(font
					(size 1.016 1.016)
					(thickness 0.1524)
				)
			)
		)
		(property "Device Type" "R1206H26"
			(at 0 -6.3754 270)
			(unlocked yes)
			(layer "F.Fab")
			(hide yes)
			(effects
				(font
					(size 1.016 1.016)
					(thickness 0.1524)
				)
			)
		)
		(duplicate_pad_numbers_are_jumpers no)
		(fp_line
			(start -1.016 2.2352)
			(end -1.016 -2.2352)
			(stroke
				(width 0.1524)
				(type default)
			)
			(layer "F.SilkS")
		)
		(fp_line
			(start 1.016 2.2352)
			(end -1.016 2.2352)
			(stroke
				(width 0.1524)
				(type default)
			)
			(layer "F.SilkS")
		)
		(fp_line
			(start -1.016 -2.2352)
			(end 1.016 -2.2352)
			(stroke
				(width 0.1524)
				(type default)
			)
			(layer "F.SilkS")
		)
		(fp_line
			(start 1.016 -2.2352)
			(end 1.016 2.2352)
			(stroke
				(width 0.1524)
				(type default)
			)
			(layer "F.SilkS")
		)
		(fp_rect
			(start -1.0922 2.3114)
			(end 1.0922 -2.3114)
			(stroke
				(width 0)
				(type default)
			)
			(fill no)
			(layer "F.CrtYd")
		)
		(fp_poly
			(pts
				(xy -1.0922 -2.3114) (xy 1.0922 -2.3114) (xy 1.0922 2.3114) (xy -1.0922 2.3114)
			)
			(stroke
				(width 0)
				(type default)
			)
			(fill no)
			(layer "F.Fab")
		)
		(pad "1" smd rect
			(at 0 -1.397 270)
			(size 1.651 1.27)
			(layers "F.Cu" "F.Mask" "F.Paste")
			(net "P12V_HDD7")
		)
		(pad "2" smd rect
			(at 0 1.397 270)
			(size 1.651 1.27)
			(layers "F.Cu" "F.Mask" "F.Paste")
			(net "12V_PRE_7")
		)
	)
	(footprint ""
		(layer "F.Cu")
		(at 212.97138 -238.61522 180)
		(property "Reference" "C7"
			(at 0 0 180)
			(layer "F.SilkS")
			(hide yes)
			(effects
				(font
					(size 1.27 1.27)
				)
			)
		)
		(property "Value" "SC1U16V3KX-5GP"
			(at 0 -2.8194 180)
			(unlocked yes)
			(layer "F.Fab")
			(hide yes)
			(effects
				(font
					(size 1.016 1.016)
					(thickness 0.1524)
				)
			)
		)
		(property "Device Type" "C603H36"
			(at 0 -4.3434 180)
			(unlocked yes)
			(layer "F.Fab")
			(hide yes)
			(effects
				(font
					(size 1.016 1.016)
					(thickness 0.1524)
				)
			)
		)
		(duplicate_pad_numbers_are_jumpers no)
		(fp_line
			(start 0.508 0)
			(end -0.508 0)
			(stroke
				(width 0.2032)
				(type default)
			)
			(layer "F.SilkS")
		)
		(fp_rect
			(start -0.5842 1.3335)
			(end 0.5842 -1.3335)
			(stroke
				(width 0)
				(type default)
			)
			(fill no)
			(layer "F.CrtYd")
		)
		(fp_rect
			(start -0.5842 1.3335)
			(end 0.5842 -1.3335)
			(stroke
				(width 0)
				(type default)
			)
			(fill no)
			(layer "F.Fab")
		)
		(pad "1" smd custom
			(at 0 -0.762 180)
			(size 0.2159 0.2159)
			(layers "F.Cu" "F.Mask" "F.Paste")
			(net "P3V3_STBY_B")
			(options
				(clearance outline)
				(anchor circle)
			)
			(primitives
				(gr_poly
					(pts
						(arc
							(start -0.3302 -0.4318)
							(mid -0.402042 -0.402042)
							(end -0.4318 -0.3302)
						)
						(arc
							(start -0.4318 0.3302)
							(mid -0.402042 0.402042)
							(end -0.3302 0.4318)
						)
						(arc
							(start 0.3302 0.4318)
							(mid 0.402042 0.402042)
							(end 0.4318 0.3302)
						)
						(arc
							(start 0.4318 -0.3302)
							(mid 0.402042 -0.402042)
							(end 0.3302 -0.4318)
						)
					)
					(width 0)
					(fill yes)
				)
			)
		)
		(pad "2" smd custom
			(at 0 0.762 180)
			(size 0.2159 0.2159)
			(layers "F.Cu" "F.Mask" "F.Paste")
			(net "GND")
			(options
				(clearance outline)
				(anchor circle)
			)
			(primitives
				(gr_poly
					(pts
						(arc
							(start -0.3302 -0.4318)
							(mid -0.402042 -0.402042)
							(end -0.4318 -0.3302)
						)
						(arc
							(start -0.4318 0.3302)
							(mid -0.402042 0.402042)
							(end -0.3302 0.4318)
						)
						(arc
							(start 0.3302 0.4318)
							(mid 0.402042 0.402042)
							(end 0.4318 0.3302)
						)
						(arc
							(start 0.4318 -0.3302)
							(mid 0.402042 -0.402042)
							(end 0.3302 -0.4318)
						)
					)
					(width 0)
					(fill yes)
				)
			)
		)
	)
	(footprint ""
		(layer "F.Cu")
		(at 478.6884 -11.176 180)
		(property "Reference" "R887"
			(at 0 0 180)
			(layer "F.SilkS")
			(hide yes)
			(effects
				(font
					(size 1.27 1.27)
				)
			)
		)
		(property "Value" "4K7R2F-GP"
			(at 0.064008 -3.993896 180)
			(unlocked yes)
			(layer "F.Fab")
			(hide yes)
			(effects
				(font
					(size 1.016 1.016)
					(thickness 0.1524)
				)
			)
		)
		(property "Device Type" "R402H16"
			(at 0.064008 -5.517896 180)
			(unlocked yes)
			(layer "F.Fab")
			(hide yes)
			(effects
				(font
					(size 1.016 1.016)
					(thickness 0.1524)
				)
			)
		)
		(duplicate_pad_numbers_are_jumpers no)
		(fp_line
			(start 0.508 -0.9398)
			(end -0.508 -0.9398)
			(stroke
				(width 0.1524)
				(type default)
			)
			(layer "F.SilkS")
		)
		(fp_line
			(start -0.508 -0.9398)
			(end -0.508 0.9398)
			(stroke
				(width 0.1524)
				(type default)
			)
			(layer "F.SilkS")
		)
		(fp_rect
			(start -0.508 0.9398)
			(end 0.508 -0.9398)
			(stroke
				(width 0)
				(type default)
			)
			(fill no)
			(layer "F.CrtYd")
		)
		(fp_rect
			(start -0.508 0.9398)
			(end 0.508 -0.9398)
			(stroke
				(width 0)
				(type default)
			)
			(fill no)
			(layer "F.Fab")
		)
		(pad "1" smd custom
			(at 0 -0.4445 180)
			(size 0.1397 0.1397)
			(layers "F.Cu" "F.Mask" "F.Paste")
			(net "SW_PWR_R_HDD35")
			(options
				(clearance outline)
				(anchor circle)
			)
			(primitives
				(gr_poly
					(pts
						(arc
							(start -0.1778 -0.2794)
							(mid -0.249642 -0.249642)
							(end -0.2794 -0.1778)
						)
						(arc
							(start -0.2794 0.1778)
							(mid -0.249642 0.249642)
							(end -0.1778 0.2794)
						)
						(arc
							(start 0.1778 0.2794)
							(mid 0.249642 0.249642)
							(end 0.2794 0.1778)
						)
						(arc
							(start 0.2794 -0.1778)
							(mid 0.249642 -0.249642)
							(end 0.1778 -0.2794)
						)
					)
					(width 0)
					(fill yes)
				)
			)
		)
		(pad "2" smd custom
			(at 0 0.4445 180)
			(size 0.1397 0.1397)
			(layers "F.Cu" "F.Mask" "F.Paste")
			(net "GND")
			(options
				(clearance outline)
				(anchor circle)
			)
			(primitives
				(gr_poly
					(pts
						(arc
							(start -0.1778 -0.2794)
							(mid -0.249642 -0.249642)
							(end -0.2794 -0.1778)
						)
						(arc
							(start -0.2794 0.1778)
							(mid -0.249642 0.249642)
							(end -0.1778 0.2794)
						)
						(arc
							(start 0.1778 0.2794)
							(mid 0.249642 0.249642)
							(end 0.2794 0.1778)
						)
						(arc
							(start 0.2794 -0.1778)
							(mid 0.249642 -0.249642)
							(end 0.1778 -0.2794)
						)
					)
					(width 0)
					(fill yes)
				)
			)
		)
	)
	(footprint ""
		(layer "F.Cu")
		(at 37.0332 -11.2776 -90)
		(property "Reference" "R128"
			(at 0 0 270)
			(layer "F.SilkS")
			(hide yes)
			(effects
				(font
					(size 1.27 1.27)
				)
			)
		)
		(property "Value" "0R2J-2-GP"
			(at 0.064008 -3.993896 270)
			(unlocked yes)
			(layer "F.Fab")
			(hide yes)
			(effects
				(font
					(size 1.016 1.016)
					(thickness 0.1524)
				)
			)
		)
		(property "Device Type" "R402H16"
			(at 0.064008 -5.517896 270)
			(unlocked yes)
			(layer "F.Fab")
			(hide yes)
			(effects
				(font
					(size 1.016 1.016)
					(thickness 0.1524)
				)
			)
		)
		(duplicate_pad_numbers_are_jumpers no)
		(fp_line
			(start -0.508 -0.9398)
			(end -0.508 0.9398)
			(stroke
				(width 0.1524)
				(type default)
			)
			(layer "F.SilkS")
		)
		(fp_line
			(start 0.508 -0.9398)
			(end -0.508 -0.9398)
			(stroke
				(width 0.1524)
				(type default)
			)
			(layer "F.SilkS")
		)
		(fp_rect
			(start -0.508 0.9398)
			(end 0.508 -0.9398)
			(stroke
				(width 0)
				(type default)
			)
			(fill no)
			(layer "F.CrtYd")
		)
		(fp_rect
			(start -0.508 0.9398)
			(end 0.508 -0.9398)
			(stroke
				(width 0)
				(type default)
			)
			(fill no)
			(layer "F.Fab")
		)
		(pad "1" smd custom
			(at 0 -0.4445 270)
			(size 0.1397 0.1397)
			(layers "F.Cu" "F.Mask" "F.Paste")
			(net "I2C_DPB_A_SDA_BUF")
			(options
				(clearance outline)
				(anchor circle)
			)
			(primitives
				(gr_poly
					(pts
						(arc
							(start -0.1778 -0.2794)
							(mid -0.249642 -0.249642)
							(end -0.2794 -0.1778)
						)
						(arc
							(start -0.2794 0.1778)
							(mid -0.249642 0.249642)
							(end -0.1778 0.2794)
						)
						(arc
							(start 0.1778 0.2794)
							(mid 0.249642 0.249642)
							(end 0.2794 0.1778)
						)
						(arc
							(start 0.2794 -0.1778)
							(mid 0.249642 -0.249642)
							(end 0.1778 -0.2794)
						)
					)
					(width 0)
					(fill yes)
				)
			)
		)
		(pad "2" smd custom
			(at 0 0.4445 270)
			(size 0.1397 0.1397)
			(layers "F.Cu" "F.Mask" "F.Paste")
			(net "TEMP1_SDA")
			(options
				(clearance outline)
				(anchor circle)
			)
			(primitives
				(gr_poly
					(pts
						(arc
							(start -0.1778 -0.2794)
							(mid -0.249642 -0.249642)
							(end -0.2794 -0.1778)
						)
						(arc
							(start -0.2794 0.1778)
							(mid -0.249642 0.249642)
							(end -0.1778 0.2794)
						)
						(arc
							(start 0.1778 0.2794)
							(mid 0.249642 0.249642)
							(end 0.2794 0.1778)
						)
						(arc
							(start 0.2794 -0.1778)
							(mid 0.249642 -0.249642)
							(end 0.1778 -0.2794)
						)
					)
					(width 0)
					(fill yes)
				)
			)
		)
	)
	(footprint ""
		(layer "F.Cu")
		(at 178.435 -26.289 180)
		(property "Reference" "Q148"
			(at 0 0 180)
			(layer "F.SilkS")
			(hide yes)
			(effects
				(font
					(size 1.27 1.27)
				)
			)
		)
		(property "Value" "AO4406AL-GP"
			(at -3.707384 -1.5367 180)
			(unlocked yes)
			(layer "F.Fab")
			(hide yes)
			(effects
				(font
					(size 1.016 1.016)
					(thickness 0.1524)
				)
			)
		)
		(property "Device Type" "SOIC8H69"
			(at -3.707384 -3.0607 180)
			(unlocked yes)
			(layer "F.Fab")
			(hide yes)
			(effects
				(font
					(size 1.016 1.016)
					(thickness 0.1524)
				)
			)
		)
		(duplicate_pad_numbers_are_jumpers no)
		(fp_line
			(start 2.1336 1.4224)
			(end 2.1336 -1.4224)
			(stroke
				(width 0.1524)
				(type default)
			)
			(layer "F.SilkS")
		)
		(fp_line
			(start 2.1336 -1.4224)
			(end -2.7432 -1.4224)
			(stroke
				(width 0.1524)
				(type default)
			)
			(layer "F.SilkS")
		)
		(fp_line
			(start -2.1844 -0.0508)
			(end -2.7178 0.508)
			(stroke
				(width 0.1524)
				(type default)
			)
			(layer "F.SilkS")
		)
		(fp_line
			(start -2.6289 3.4417)
			(end -2.6289 1.4732)
			(stroke
				(width 0.381)
				(type default)
			)
			(layer "F.SilkS")
		)
		(fp_line
			(start -2.7178 -0.508)
			(end -2.1844 -0.0508)
			(stroke
				(width 0.1524)
				(type default)
			)
			(layer "F.SilkS")
		)
		(fp_line
			(start -2.7432 1.4224)
			(end 2.1336 1.4224)
			(stroke
				(width 0.1524)
				(type default)
			)
			(layer "F.SilkS")
		)
		(fp_line
			(start -2.7432 1.4224)
			(end -2.6416 1.4224)
			(stroke
				(width 0.1524)
				(type default)
			)
			(layer "F.SilkS")
		)
		(fp_line
			(start -2.7432 -1.4224)
			(end -2.7432 1.4224)
			(stroke
				(width 0.1524)
				(type default)
			)
			(layer "F.SilkS")
		)
		(fp_poly
			(pts
				(xy -2.2098 -1.4224) (xy -2.2098 1.4224) (xy 2.2098 1.4224) (xy 2.2098 -1.4224)
			)
			(stroke
				(width 0)
				(type default)
			)
			(fill yes)
			(layer "F.SilkS")
		)
		(fp_rect
			(start -2.450084 2.999994)
			(end 2.450084 -2.999994)
			(stroke
				(width 0)
				(type default)
			)
			(fill no)
			(layer "F.CrtYd")
		)
		(fp_poly
			(pts
				(xy -2.8194 3.6322) (xy -2.8194 -3.6322) (xy 2.8194 -3.6322) (xy 2.8194 1.18364) (xy 2.450084 1.18364)
				(xy 2.450084 -2.999994) (xy -2.450084 -2.999994) (xy -2.450084 2.999994) (xy 2.450084 2.999994)
				(xy 2.450084 1.18618) (xy 2.8194 1.18618) (xy 2.8194 3.6322)
			)
			(stroke
				(width 0)
				(type default)
			)
			(fill no)
			(layer "F.CrtYd")
		)
		(fp_rect
			(start -2.8194 3.6322)
			(end 2.8194 -3.6322)
			(stroke
				(width 0)
				(type default)
			)
			(fill no)
			(layer "F.Fab")
		)
		(pad "1" smd rect
			(at -1.905 2.54 180)
			(size 0.635 1.651)
			(layers "F.Cu" "F.Mask" "F.Paste")
			(net "P5V_HDD29")
		)
		(pad "2" smd rect
			(at -0.635 2.54 180)
			(size 0.635 1.651)
			(layers "F.Cu" "F.Mask" "F.Paste")
			(net "P5V_HDD29")
		)
		(pad "3" smd rect
			(at 0.635 2.54 180)
			(size 0.635 1.651)
			(layers "F.Cu" "F.Mask" "F.Paste")
			(net "P5V_HDD29")
		)
		(pad "4" smd rect
			(at 1.905 2.54 180)
			(size 0.635 1.651)
			(layers "F.Cu" "F.Mask" "F.Paste")
			(net "SW_HDD_P29")
		)
		(pad "5" smd rect
			(at 1.905 -2.54 180)
			(size 0.635 1.651)
			(layers "F.Cu" "F.Mask" "F.Paste")
			(net "P5V_B_2")
		)
		(pad "6" smd rect
			(at 0.635 -2.54 180)
			(size 0.635 1.651)
			(layers "F.Cu" "F.Mask" "F.Paste")
			(net "P5V_B_2")
		)
		(pad "7" smd rect
			(at -0.635 -2.54 180)
			(size 0.635 1.651)
			(layers "F.Cu" "F.Mask" "F.Paste")
			(net "P5V_B_2")
		)
		(pad "8" smd rect
			(at -1.905 -2.54 180)
			(size 0.635 1.651)
			(layers "F.Cu" "F.Mask" "F.Paste")
			(net "P5V_B_2")
		)
	)
)
